# BASEBOARD_FAB2 (Tioga Pass) — schematic netlist excerpt (pin names and nets, part order shuffled) for the footprints in the layout excerpt that follows; sources: Cadence DE-HDL packaged netlist, KiCad conversion of Wiwynn_Tioga_Pass_MB.brd

C3G4  CAP  10UF 4V 20% X6S  pkg 0603LF  page 233 : A = PVPP_GHJ ; B = GND
R25W20  120R2F-GP  1%  pkg RCL_GP  page 151 : \1\ = GND ; \2\ = BMC_M_A8

(kicad_pcb
	(version 20260206)
	(generator "pcbnew")
	(generator_version "10.0")
	(general
		(thickness 1.6)
		(legacy_teardrops no)
	)
	(paper "A4")
	(title_block
		(title "Wiwynn_Tioga_Pass_MB.brd")
		(comment 1 "Tioga Pass / footprints 1640-1641 of 4770")
	)
	(layers
		(0 "F.Cu" signal "TOP")
		(4 "In1.Cu" signal "L2GND")
		(6 "In2.Cu" signal "L3")
		(8 "In3.Cu" signal "L4GND")
		(10 "In4.Cu" signal "L5")
		(12 "In5.Cu" signal "L6GND")
		(14 "In6.Cu" signal "L7VCC")
		(16 "In7.Cu" signal "L8VCC")
		(18 "In8.Cu" signal "L9GND")
		(20 "In9.Cu" signal "L10")
		(22 "In10.Cu" signal "L11GND")
		(24 "In11.Cu" signal "L12")
		(26 "In12.Cu" signal "L13GND")
		(2 "B.Cu" signal "BOTTOM")
		(9 "F.Adhes" user "F.Adhesive")
		(11 "B.Adhes" user "B.Adhesive")
		(13 "F.Paste" user "Package Geometry/Pastemask Top")
		(15 "B.Paste" user "Package Geometry/Pastemask Bottom")
		(5 "F.SilkS" user "Ref Des/Silkscreen Top")
		(7 "B.SilkS" user "Ref Des/Silkscreen Bottom")
		(1 "F.Mask" user "Board Geometry/Soldermask Top")
		(3 "B.Mask" user "Board Geometry/Soldermask Bottom")
		(17 "Dwgs.User" user "User.Drawings")
		(19 "Cmts.User" user "User.Comments")
		(21 "Eco1.User" user "User.Eco1")
		(23 "Eco2.User" user "User.Eco2")
		(25 "Edge.Cuts" user "Board Geometry/Outline")
		(27 "Margin" user)
		(31 "F.CrtYd" user "Package Geometry/Place Bound Top")
		(29 "B.CrtYd" user "Package Geometry/Place Bound Bottom")
		(35 "F.Fab" user "Ref Des/Assembly Top")
		(33 "B.Fab" user "Ref Des/Assembly Bottom")
	)
	(footprint ""
		(layer "F.Cu")
		(at 449.69938 -37.1475 90)
		(property "Reference" "R25W20"
			(at 0 0 90)
			(layer "F.SilkS")
			(hide yes)
			(effects
				(font
					(size 1.27 1.27)
				)
			)
		)
		(property "Value" "*"
			(at 0.064008 -4.108196 90)
			(unlocked yes)
			(layer "F.Fab")
			(hide yes)
			(effects
				(font
					(size 1.27 1.016)
					(thickness 0.1524)
				)
			)
		)
		(property "Device Type" "120R2F-GP_RCL_GP-120R2F-GP,64.A"
			(at 0.064008 -5.632196 90)
			(unlocked yes)
			(layer "F.Fab")
			(hide yes)
			(effects
				(font
					(size 1.27 1.016)
					(thickness 0.1524)
				)
			)
		)
		(duplicate_pad_numbers_are_jumpers no)
		(fp_line
			(start 0.508 -0.9398)
			(end -0.508 -0.9398)
			(stroke
				(width 0.1524)
				(type default)
			)
			(layer "F.SilkS")
		)
		(fp_line
			(start -0.508 -0.9398)
			(end -0.508 0.9398)
			(stroke
				(width 0.1524)
				(type default)
			)
			(layer "F.SilkS")
		)
		(fp_rect
			(start -0.508 0.9398)
			(end 0.508 -0.9398)
			(stroke
				(width 0)
				(type default)
			)
			(fill no)
			(layer "F.CrtYd")
		)
		(fp_rect
			(start -0.508 0.9398)
			(end 0.508 -0.9398)
			(stroke
				(width 0)
				(type default)
			)
			(fill no)
			(layer "F.Fab")
		)
		(pad "1" smd custom
			(at 0 -0.4445 90)
			(size 0.1397 0.1397)
			(layers "F.Cu" "F.Mask" "F.Paste")
			(net "GND")
			(options
				(clearance outline)
				(anchor circle)
			)
			(primitives
				(gr_poly
					(pts
						(arc
							(start -0.1778 -0.2794)
							(mid -0.249642 -0.249642)
							(end -0.2794 -0.1778)
						)
						(arc
							(start -0.2794 0.1778)
							(mid -0.249642 0.249642)
							(end -0.1778 0.2794)
						)
						(arc
							(start 0.1778 0.2794)
							(mid 0.249642 0.249642)
							(end 0.2794 0.1778)
						)
						(arc
							(start 0.2794 -0.1778)
							(mid 0.249642 -0.249642)
							(end 0.1778 -0.2794)
						)
					)
					(width 0)
					(fill yes)
				)
			)
		)
		(pad "2" smd custom
			(at 0 0.4445 90)
			(size 0.1397 0.1397)
			(layers "F.Cu" "F.Mask" "F.Paste")
			(net "BMC_M_A8")
			(options
				(clearance outline)
				(anchor circle)
			)
			(primitives
				(gr_poly
					(pts
						(arc
							(start -0.1778 -0.2794)
							(mid -0.249642 -0.249642)
							(end -0.2794 -0.1778)
						)
						(arc
							(start -0.2794 0.1778)
							(mid -0.249642 0.249642)
							(end -0.1778 0.2794)
						)
						(arc
							(start 0.1778 0.2794)
							(mid 0.249642 0.249642)
							(end 0.2794 0.1778)
						)
						(arc
							(start 0.2794 -0.1778)
							(mid 0.249642 -0.249642)
							(end 0.1778 -0.2794)
						)
					)
					(width 0)
					(fill yes)
				)
			)
		)
	)
	(footprint ""
		(layer "F.Cu")
		(at 155.2956 -12.954 90)
		(property "Reference" "C3G4"
			(at 0 0 90)
			(layer "F.SilkS")
			(hide yes)
			(effects
				(font
					(size 1.27 1.27)
				)
			)
		)
		(property "Value" ""
			(at 0 0 90)
			(layer "F.Fab")
			(effects
				(font
					(size 1.27 1.27)
				)
			)
		)
		(duplicate_pad_numbers_are_jumpers no)
		(fp_poly
			(pts
				(xy -0.4953 -0.2032) (xy 0.4953 -0.2032) (xy 0.4953 1.6002) (xy -0.4953 1.6002)
			)
			(stroke
				(width 0)
				(type default)
			)
			(fill no)
			(layer "F.CrtYd")
		)
		(fp_line
			(start 0.4953 -0.2032)
			(end 0.4953 1.6002)
			(stroke
				(width 0.1)
				(type default)
			)
			(layer "F.Fab")
		)
		(fp_line
			(start -0.4953 -0.2032)
			(end 0.4953 -0.2032)
			(stroke
				(width 0.1)
				(type default)
			)
			(layer "F.Fab")
		)
		(fp_line
			(start 0.4953 1.6002)
			(end -0.4953 1.6002)
			(stroke
				(width 0.1)
				(type default)
			)
			(layer "F.Fab")
		)
		(fp_line
			(start -0.4953 1.6002)
			(end -0.4953 -0.2032)
			(stroke
				(width 0.1)
				(type default)
			)
			(layer "F.Fab")
		)
		(pad "1" smd rect
			(at 0 0 90)
			(size 0.762 0.889)
			(layers "F.Cu" "F.Mask" "F.Paste")
			(net "PVPP_GHJ")
		)
		(pad "2" smd rect
			(at 0 1.397 90)
			(size 0.762 0.889)
			(layers "F.Cu" "F.Mask" "F.Paste")
			(net "GND")
		)
		(zone
			(layer "F.Cu")
			(hatch none 0.5)
			(connect_pads
				(clearance 0)
			)
			(min_thickness 0.25)
			(keepout
				(tracks not_allowed)
				(vias allowed)
				(pads allowed)
				(copperpour not_allowed)
				(footprints allowed)
			)
			(placement
				(enabled no)
				(sheetname "")
			)
			(fill
				(thermal_gap 0.5)
				(thermal_bridge_width 0.5)
				(island_removal_mode 0)
			)
			(polygon
				(pts
					(xy 155.7401 -12.573) (xy 155.7401 -13.335) (xy 156.2481 -13.335) (xy 156.2481 -12.573)
				)
			)
		)
	)
)
